(kicad_pcb
	(version 20241229)
	(generator "pcbnew")
	(generator_version "9.0")
	(general
		(thickness 1.61)
		(legacy_teardrops no)
	)
	(paper "A3")
	(title_block
		(title "SO-DIMM DDR5 Tester")
		(date "2025-11-26")
		(rev "1.3.0")
		(comment 9 "footprints 213-217 of 627")
	)
	(layers
		(0 "F.Cu" signal)
		(4 "In1.Cu" power)
		(6 "In2.Cu" mixed)
		(8 "In3.Cu" power)
		(10 "In4.Cu" mixed)
		(12 "In5.Cu" power)
		(14 "In6.Cu" mixed)
		(16 "In7.Cu" power)
		(18 "In8.Cu" power)
		(20 "In9.Cu" mixed)
		(22 "In10.Cu" power)
		(2 "B.Cu" signal)
		(9 "F.Adhes" user "F.Adhesive")
		(11 "B.Adhes" user "B.Adhesive")
		(13 "F.Paste" user)
		(15 "B.Paste" user)
		(5 "F.SilkS" user "F.Silkscreen")
		(7 "B.SilkS" user "B.Silkscreen")
		(1 "F.Mask" user)
		(3 "B.Mask" user)
		(17 "Dwgs.User" user "User.Drawings")
		(19 "Cmts.User" user "User.Comments")
		(21 "Eco1.User" user "User.Eco1")
		(23 "Eco2.User" user "User.Eco2")
		(25 "Edge.Cuts" user)
		(27 "Margin" user)
		(31 "F.CrtYd" user "F.Courtyard")
		(29 "B.CrtYd" user "B.Courtyard")
		(35 "F.Fab" user)
		(33 "B.Fab" user)
	)
	(footprint "antmicro-footprints:Conn_JST_SH_1x4_BM04B-SRSS-TB-LF-SN"
		(layer "F.Cu")
		(at 157.9 173.05)
		(property "Reference" "J8"
			(at 1.9 2.65 0)
			(layer "F.SilkS")
			(effects
				(font
					(size 0.7 0.7)
					(thickness 0.15)
				)
				(justify left bottom)
			)
		)
		(property "Value" "JST_SH_1x4_BM04B-SRSS-TB-LF-SN"
			(at 0 3.1 0)
			(layer "F.Fab")
			(effects
				(font
					(size 0.7 0.7)
					(thickness 0.15)
				)
				(justify left bottom)
			)
		)
		(property "Datasheet" "https://www.jst-mfg.com/product/pdf/eng/eSH.pdf"
			(at 0 0 0)
			(layer "F.Fab")
			(hide yes)
			(effects
				(font
					(size 1.27 1.27)
					(thickness 0.15)
				)
			)
		)
		(property "Author" "Antmicro"
			(at 0 0 0)
			(layer "F.Fab")
			(hide yes)
			(effects
				(font
					(size 1 1)
					(thickness 0.15)
				)
			)
		)
		(property "License" "Apache-2.0"
			(at 0 0 0)
			(layer "F.Fab")
			(hide yes)
			(effects
				(font
					(size 1 1)
					(thickness 0.15)
				)
			)
		)
		(property "MPN" "BM04B-SRSS-TB(LF)(SN) "
			(at 0 0 0)
			(layer "F.Fab")
			(hide yes)
			(effects
				(font
					(size 1 1)
					(thickness 0.15)
				)
			)
		)
		(property "Manufacturer" "JST Automotive Connectors"
			(at 0 0 0)
			(layer "F.Fab")
			(hide yes)
			(effects
				(font
					(size 1 1)
					(thickness 0.15)
				)
			)
		)
		(sheetname "/Supply/")
		(sheetfile "supply.kicad_sch")
		(attr smd)
		(fp_line
			(start -2.999 0.1765)
			(end -2.999 1.0505)
			(stroke
				(width 0.15)
				(type solid)
			)
			(layer "F.SilkS")
		)
		(fp_line
			(start -2.999 1.0505)
			(end -2.201 1.0505)
			(stroke
				(width 0.15)
				(type solid)
			)
			(layer "F.SilkS")
		)
		(fp_line
			(start -1.7005 -1.8495)
			(end 1.7015 -1.8495)
			(stroke
				(width 0.15)
				(type solid)
			)
			(layer "F.SilkS")
		)
		(fp_line
			(start 2.9995 0.1765)
			(end 2.9995 1.0505)
			(stroke
				(width 0.15)
				(type solid)
			)
			(layer "F.SilkS")
		)
		(fp_line
			(start 2.9995 1.0505)
			(end 2.2015 1.0505)
			(stroke
				(width 0.15)
				(type solid)
			)
			(layer "F.SilkS")
		)
		(fp_circle
			(center -2 1.5)
			(end -1.949 1.5)
			(stroke
				(width 0.15)
				(type solid)
			)
			(fill yes)
			(layer "F.SilkS")
		)
		(fp_rect
			(start -3.5 -2.1)
			(end 3.5 2.2)
			(stroke
				(width 0.05)
				(type solid)
			)
			(fill no)
			(layer "F.CrtYd")
		)
		(fp_line
			(start -2.9995 -1.8495)
			(end 2.9995 -1.8495)
			(stroke
				(width 0.15)
				(type solid)
			)
			(layer "F.Fab")
		)
		(fp_line
			(start -2.9995 1.0165)
			(end -2.9995 -1.8495)
			(stroke
				(width 0.15)
				(type solid)
			)
			(layer "F.Fab")
		)
		(fp_line
			(start -1.991 1.7785)
			(end -2.9995 0.9657)
			(stroke
				(width 0.15)
				(type solid)
			)
			(layer "F.Fab")
		)
		(fp_line
			(start 2.9995 -1.8495)
			(end 3.008 1.7785)
			(stroke
				(width 0.15)
				(type solid)
			)
			(layer "F.Fab")
		)
		(fp_line
			(start 3.008 1.7785)
			(end -1.991 1.7785)
			(stroke
				(width 0.15)
				(type solid)
			)
			(layer "F.Fab")
		)
		(pad "1" smd rect
			(at -1.4995 1.3765)
			(size 0.6 1.55)
			(layers "F.Cu" "F.Mask" "F.Paste")
			(net 1 "GND")
			(pinfunction "Pin_1")
			(pintype "passive")
		)
		(pad "2" smd rect
			(at -0.5015 1.3765)
			(size 0.6 1.55)
			(layers "F.Cu" "F.Mask" "F.Paste")
			(net 201 "+5V")
			(pinfunction "Pin_2")
			(pintype "passive")
		)
		(pad "3" smd rect
			(at 0.4995 1.3765)
			(size 0.6 1.55)
			(layers "F.Cu" "F.Mask" "F.Paste")
			(net 331 "unconnected-(J8-Pin_3-Pad3)")
			(pinfunction "Pin_3")
			(pintype "passive+no_connect")
		)
		(pad "4" smd rect
			(at 1.4995 1.3765)
			(size 0.6 1.55)
			(layers "F.Cu" "F.Mask" "F.Paste")
			(net 332 "Net-(J8-Pin_4)")
			(pinfunction "Pin_4")
			(pintype "passive")
		)
		(pad "MP" smd rect
			(at -2.7995 -1.1485)
			(size 1.2 1.8)
			(layers "F.Cu" "F.Mask" "F.Paste")
			(net 1 "GND")
			(pinfunction "MP")
			(pintype "passive")
		)
		(pad "MP" smd rect
			(at 2.8005 -1.1485)
			(size 1.2 1.8)
			(layers "F.Cu" "F.Mask" "F.Paste")
			(net 1 "GND")
			(pinfunction "MP")
			(pintype "passive")
		)
	)
	(footprint "antmicro-footprints:LED_RGY_1.6x1.6mm_APTF1616"
		(layer "F.Cu")
		(at 97.350501 116.426 -90)
		(descr "1.6 x 1.6 mm Full-Color Surface Mount LED")
		(tags "LED")
		(property "Reference" "D9"
			(at 0 -1.2 90)
			(layer "F.SilkS")
			(hide yes)
			(effects
				(font
					(size 0.7 0.7)
					(thickness 0.15)
				)
				(justify left bottom)
			)
		)
		(property "Value" "LED_RGY_0606_APTF1616SURKCGKSYKC"
			(at 0 2 270)
			(layer "F.Fab")
			(effects
				(font
					(size 0.7 0.7)
					(thickness 0.15)
				)
				(justify left bottom)
			)
		)
		(property "Datasheet" "http://www.mouser.com/datasheet/2/216/APTF1616SURKCGKSYKC-1145193.pdf"
			(at 0 0 270)
			(layer "F.Fab")
			(hide yes)
			(effects
				(font
					(size 1.27 1.27)
					(thickness 0.15)
				)
			)
		)
		(property "Description" "Standard LEDs - SMD RGY 1616 SMD"
			(at -19.075499 213.776501 0)
			(layer "F.Fab")
			(hide yes)
			(effects
				(font
					(size 1.27 1.27)
					(thickness 0.15)
				)
			)
		)
		(property "Author" "Antmicro"
			(at -19.075499 213.776501 0)
			(layer "F.Fab")
			(hide yes)
			(effects
				(font
					(size 1 1)
					(thickness 0.15)
				)
			)
		)
		(property "License" "Apache-2.0"
			(at -19.075499 213.776501 0)
			(layer "F.Fab")
			(hide yes)
			(effects
				(font
					(size 1 1)
					(thickness 0.15)
				)
			)
		)
		(property "MPN" "APTF1616SURKCGKSYKC"
			(at -19.075499 213.776501 0)
			(layer "F.Fab")
			(hide yes)
			(effects
				(font
					(size 1 1)
					(thickness 0.15)
				)
			)
		)
		(property "Manufacturer" "Kingbright"
			(at -19.075499 213.776501 0)
			(layer "F.Fab")
			(hide yes)
			(effects
				(font
					(size 1 1)
					(thickness 0.15)
				)
			)
		)
		(sheetname "/DDR5 SODIMM/")
		(sheetfile "ddr5-sodimm.kicad_sch")
		(attr smd)
		(fp_line
			(start -0.35 0.8)
			(end 0.35 0.8)
			(stroke
				(width 0.15)
				(type solid)
			)
			(layer "F.SilkS")
		)
		(fp_line
			(start 0.8 0.148)
			(end 0.8 -0.102)
			(stroke
				(width 0.15)
				(type solid)
			)
			(layer "F.SilkS")
		)
		(fp_line
			(start -0.8 -0.15)
			(end -0.801 0.15)
			(stroke
				(width 0.15)
				(type solid)
			)
			(layer "F.SilkS")
		)
		(fp_line
			(start 0.35 -0.802)
			(end -0.35 -0.802)
			(stroke
				(width 0.15)
				(type solid)
			)
			(layer "F.SilkS")
		)
		(fp_circle
			(center -1.05 -0.95)
			(end -1.101 -0.999)
			(stroke
				(width 0.15)
				(type solid)
			)
			(fill yes)
			(layer "F.SilkS")
		)
		(fp_rect
			(start 1.3 1.1)
			(end -1.3 -1.1)
			(stroke
				(width 0.05)
				(type solid)
			)
			(fill no)
			(layer "F.CrtYd")
		)
		(fp_rect
			(start -0.801 -0.802)
			(end 0.8 0.801)
			(stroke
				(width 0.15)
				(type solid)
			)
			(fill no)
			(layer "F.Fab")
		)
		(pad "1" smd rect
			(at -0.874 -0.499 180)
			(size 0.5 0.85)
			(layers "F.Cu" "F.Mask" "F.Paste")
			(net 200 "+3V3")
			(pinfunction "A")
			(pintype "passive")
		)
		(pad "2" smd rect
			(at 0.874 -0.499 180)
			(size 0.5 0.85)
			(layers "F.Cu" "F.Mask" "F.Paste")
			(net 301 "Net-(D9-C_{R})")
			(pinfunction "C_{R}")
			(pintype "passive")
		)
		(pad "3" smd rect
			(at 0.874 0.498 180)
			(size 0.5 0.85)
			(layers "F.Cu" "F.Mask" "F.Paste")
			(net 302 "Net-(D9-C_{G})")
			(pinfunction "C_{G}")
			(pintype "passive")
		)
		(pad "4" smd rect
			(at -0.874 0.498 180)
			(size 0.5 0.85)
			(layers "F.Cu" "F.Mask" "F.Paste")
			(net 312 "Net-(D9-C_{Y})")
			(pinfunction "C_{Y}")
			(pintype "passive")
		)
	)
	(footprint "antmicro-footprints:C_0603_1608Metric"
		(layer "F.Cu")
		(at 78.149 150.85 90)
		(descr "Capacitor SMD 0603")
		(tags "capacitor 0603")
		(property "Reference" "C109"
			(at -1.42757 -1.000252 90)
			(layer "F.SilkS")
			(hide yes)
			(effects
				(font
					(size 0.7 0.7)
					(thickness 0.15)
				)
				(justify left bottom)
			)
		)
		(property "Value" "C_10u_25V_0603"
			(at -1.42757 1.770288 90)
			(layer "F.Fab")
			(effects
				(font
					(size 0.7 0.7)
					(thickness 0.15)
				)
				(justify left bottom)
			)
		)
		(property "Datasheet" "https://product.tdk.com/en/search/capacitor/ceramic/mlcc/info?part_no=C1608X5R1E106M080AC"
			(at 0 0 90)
			(layer "F.Fab")
			(hide yes)
			(effects
				(font
					(size 1.27 1.27)
					(thickness 0.15)
				)
			)
		)
		(property "Author" "Antmicro"
			(at 228.999 72.701 0)
			(layer "F.Fab")
			(hide yes)
			(effects
				(font
					(size 1 1)
					(thickness 0.15)
				)
			)
		)
		(property "Dielectric" ""
			(at 228.999 72.701 0)
			(layer "F.Fab")
			(hide yes)
			(effects
				(font
					(size 1 1)
					(thickness 0.15)
				)
			)
		)
		(property "License" "Apache-2.0"
			(at 228.999 72.701 0)
			(layer "F.Fab")
			(hide yes)
			(effects
				(font
					(size 1 1)
					(thickness 0.15)
				)
			)
		)
		(property "MPN" "C1608X5R1E106M080AC"
			(at 228.999 72.701 0)
			(layer "F.Fab")
			(hide yes)
			(effects
				(font
					(size 1 1)
					(thickness 0.15)
				)
			)
		)
		(property "Manufacturer" "TDK"
			(at 228.999 72.701 0)
			(layer "F.Fab")
			(hide yes)
			(effects
				(font
					(size 1 1)
					(thickness 0.15)
				)
			)
		)
		(property "Val" "10u/25V"
			(at 228.999 72.701 0)
			(layer "F.Fab")
			(hide yes)
			(effects
				(font
					(size 1 1)
					(thickness 0.15)
				)
			)
		)
		(property "Voltage" ""
			(at 228.999 72.701 0)
			(layer "F.Fab")
			(hide yes)
			(effects
				(font
					(size 1 1)
					(thickness 0.15)
				)
			)
		)
		(sheetname "/Debug FTDI/")
		(sheetfile "debug-ftdi.kicad_sch")
		(attr smd)
		(fp_line
			(start -0.3 -0.3)
			(end 0.3 -0.3)
			(stroke
				(width 0.15)
				(type solid)
			)
			(layer "F.SilkS")
		)
		(fp_line
			(start -0.3 0.3)
			(end 0.3 0.3)
			(stroke
				(width 0.15)
				(type solid)
			)
			(layer "F.SilkS")
		)
		(fp_rect
			(start -1.24 -0.7)
			(end 1.24 0.7)
			(stroke
				(width 0.05)
				(type solid)
			)
			(fill no)
			(layer "F.CrtYd")
		)
		(fp_rect
			(start -0.8 -0.4)
			(end 0.8 0.4)
			(stroke
				(width 0.15)
				(type solid)
			)
			(fill no)
			(layer "F.Fab")
		)
		(pad "1" smd roundrect
			(at -0.7 0 90)
			(size 0.6 0.8)
			(layers "F.Cu" "F.Mask" "F.Paste")
			(roundrect_rratio 0.2)
			(net 1 "GND")
			(pintype "passive")
		)
		(pad "2" smd roundrect
			(at 0.7 0 90)
			(size 0.6 0.8)
			(layers "F.Cu" "F.Mask" "F.Paste")
			(roundrect_rratio 0.2)
			(net 2 "/Debug FTDI/VBUS")
			(pintype "passive")
		)
	)
	(footprint "antmicro-footprints:C_0402_1005Metric"
		(layer "F.Cu")
		(at 181.566 154.05)
		(descr "Capacitor SMD 0402")
		(tags "capacitor SMD 0402")
		(property "Reference" "C218"
			(at 0 -0.699 0)
			(layer "F.SilkS")
			(hide yes)
			(effects
				(font
					(size 0.7 0.7)
					(thickness 0.15)
				)
				(justify left bottom)
			)
		)
		(property "Value" "C_10u_6.3V_0402"
			(at -1.022927 2.155213 0)
			(layer "F.Fab")
			(effects
				(font
					(size 0.7 0.7)
					(thickness 0.15)
				)
				(justify left bottom)
			)
		)
		(property "Datasheet" "https://www.murata.com/products/productdetail?partno=GRM155R60J106ME15%23"
			(at 0 0 0)
			(layer "F.Fab")
			(hide yes)
			(effects
				(font
					(size 1.27 1.27)
					(thickness 0.15)
				)
			)
		)
		(property "Author" "Antmicro"
			(at 0 0 0)
			(layer "F.Fab")
			(hide yes)
			(effects
				(font
					(size 1 1)
					(thickness 0.15)
				)
			)
		)
		(property "Dielectric" "X5R"
			(at 0 0 0)
			(layer "F.Fab")
			(hide yes)
			(effects
				(font
					(size 1 1)
					(thickness 0.15)
				)
			)
		)
		(property "License" "Apache-2.0"
			(at 0 0 0)
			(layer "F.Fab")
			(hide yes)
			(effects
				(font
					(size 1 1)
					(thickness 0.15)
				)
			)
		)
		(property "MPN" "GRM155R60J106ME15D"
			(at 0 0 0)
			(layer "F.Fab")
			(hide yes)
			(effects
				(font
					(size 1 1)
					(thickness 0.15)
				)
			)
		)
		(property "Manufacturer" "Murata"
			(at 0 0 0)
			(layer "F.Fab")
			(hide yes)
			(effects
				(font
					(size 1 1)
					(thickness 0.15)
				)
			)
		)
		(property "Val" "10u"
			(at 0 0 0)
			(layer "F.Fab")
			(hide yes)
			(effects
				(font
					(size 1 1)
					(thickness 0.15)
				)
			)
		)
		(property "Voltage" "6.3V"
			(at 0 0 0)
			(layer "F.Fab")
			(hide yes)
			(effects
				(font
					(size 1 1)
					(thickness 0.15)
				)
			)
		)
		(sheetname "/Supply/")
		(sheetfile "supply.kicad_sch")
		(attr smd)
		(fp_rect
			(start -0.9659 -0.481258)
			(end 0.9649 0.458742)
			(stroke
				(width 0.05)
				(type solid)
			)
			(fill no)
			(layer "F.CrtYd")
		)
		(fp_line
			(start -0.499 -0.25)
			(end 0.499 -0.25)
			(stroke
				(width 0.15)
				(type solid)
			)
			(layer "F.Fab")
		)
		(fp_line
			(start -0.499 0.248)
			(end -0.499 -0.25)
			(stroke
				(width 0.15)
				(type solid)
			)
			(layer "F.Fab")
		)
		(fp_line
			(start 0.499 -0.25)
			(end 0.499 0.248)
			(stroke
				(width 0.15)
				(type solid)
			)
			(layer "F.Fab")
		)
		(fp_line
			(start 0.499 0.248)
			(end -0.499 0.248)
			(stroke
				(width 0.15)
				(type solid)
			)
			(layer "F.Fab")
		)
		(pad "1" smd roundrect
			(at -0.484 0)
			(size 0.59 0.64)
			(layers "F.Cu" "F.Mask" "F.Paste")
			(roundrect_rratio 0.25)
			(net 1 "GND")
			(pintype "passive")
		)
		(pad "2" smd roundrect
			(at 0.484 0)
			(size 0.59 0.64)
			(layers "F.Cu" "F.Mask" "F.Paste")
			(roundrect_rratio 0.25)
			(net 206 "+1V1")
			(pintype "passive")
		)
	)
	(footprint "antmicro-footprints:C_Pol_EIA-D"
		(layer "F.Cu")
		(at 125.000501 193.976 -90)
		(property "Reference" "C12"
			(at 0 -2.6 90)
			(layer "F.SilkS")
			(hide yes)
			(effects
				(font
					(size 0.7 0.7)
					(thickness 0.15)
				)
				(justify right bottom)
			)
		)
		(property "Value" "C_Pol_1m_2.5V_KEMET-T520-D"
			(at 0 3.4 90)
			(layer "F.Fab")
			(effects
				(font
					(size 0.7 0.7)
					(thickness 0.15)
				)
				(justify right bottom)
			)
		)
		(property "Datasheet" "https://content.kemet.com/datasheets/KEM_T2076_T52X-530.pdf"
			(at 0 0 270)
			(layer "F.Fab")
			(hide yes)
			(effects
				(font
					(size 1.27 1.27)
					(thickness 0.15)
				)
			)
		)
		(property "Author" "Antmicro"
			(at -68.975499 318.976501 0)
			(layer "F.Fab")
			(hide yes)
			(effects
				(font
					(size 1 1)
					(thickness 0.15)
				)
			)
		)
		(property "License" "Apache-2.0"
			(at -68.975499 318.976501 0)
			(layer "F.Fab")
			(hide yes)
			(effects
				(font
					(size 1 1)
					(thickness 0.15)
				)
			)
		)
		(property "MPN" "T520D108M2R5ATE030"
			(at -68.975499 318.976501 0)
			(layer "F.Fab")
			(hide yes)
			(effects
				(font
					(size 1 1)
					(thickness 0.15)
				)
			)
		)
		(property "Manufacturer" "KEMET"
			(at -68.975499 318.976501 0)
			(layer "F.Fab")
			(hide yes)
			(effects
				(font
					(size 1 1)
					(thickness 0.15)
				)
			)
		)
		(property "Val" "1000u/2.5V"
			(at -68.975499 318.976501 0)
			(layer "F.Fab")
			(hide yes)
			(effects
				(font
					(size 1 1)
					(thickness 0.15)
				)
			)
		)
		(property "Voltage" "2.5V"
			(at -68.975499 318.976501 0)
			(layer "F.Fab")
			(hide yes)
			(effects
				(font
					(size 1 1)
					(thickness 0.15)
				)
			)
		)
		(sheetname "/FPGA power/")
		(sheetfile "fpga-power.kicad_sch")
		(zone_connect 2)
		(attr smd)
		(fp_line
			(start -3.58 2.2)
			(end -3.58 1.6)
			(stroke
				(width 0.15)
				(type solid)
			)
			(layer "F.SilkS")
		)
		(fp_line
			(start 3.6 2.2)
			(end -3.58 2.2)
			(stroke
				(width 0.15)
				(type solid)
			)
			(layer "F.SilkS")
		)
		(fp_line
			(start 3.6 1.6)
			(end 3.6 2.2)
			(stroke
				(width 0.15)
				(type solid)
			)
			(layer "F.SilkS")
		)
		(fp_line
			(start -3.58 -1.6)
			(end -3.58 -2.2)
			(stroke
				(width 0.15)
				(type solid)
			)
			(layer "F.SilkS")
		)
		(fp_line
			(start -4.3 -1.825)
			(end -3.9 -1.825)
			(stroke
				(width 0.12)
				(type solid)
			)
			(layer "F.SilkS")
		)
		(fp_line
			(start -4.1 -2.025)
			(end -4.1 -1.625)
			(stroke
				(width 0.12)
				(type solid)
			)
			(layer "F.SilkS")
		)
		(fp_line
			(start -3.58 -2.2)
			(end 3.6 -2.2)
			(stroke
				(width 0.15)
				(type solid)
			)
			(layer "F.SilkS")
		)
		(fp_line
			(start 3.6 -2.2)
			(end 3.6 -1.6)
			(stroke
				(width 0.15)
				(type solid)
			)
			(layer "F.SilkS")
		)
		(fp_line
			(start -3.77 2.4)
			(end -3.77 1.51)
			(stroke
				(width 0.05)
				(type solid)
			)
			(layer "F.CrtYd")
		)
		(fp_line
			(start 3.77 2.4)
			(end -3.77 2.4)
			(stroke
				(width 0.05)
				(type solid)
			)
			(layer "F.CrtYd")
		)
		(fp_line
			(start -4.505 1.51)
			(end -4.505 -1.5)
			(stroke
				(width 0.05)
				(type solid)
			)
			(layer "F.CrtYd")
		)
		(fp_line
			(start -3.77 1.51)
			(end -4.505 1.51)
			(stroke
				(width 0.05)
				(type solid)
			)
			(layer "F.CrtYd")
		)
		(fp_line
			(start 3.77 1.51)
			(end 3.77 2.4)
			(stroke
				(width 0.05)
				(type solid)
			)
			(layer "F.CrtYd")
		)
		(fp_line
			(start 4.505 1.51)
			(end 3.77 1.51)
			(stroke
				(width 0.05)
				(type solid)
			)
			(layer "F.CrtYd")
		)
		(fp_line
			(start -3.775 -1.5)
			(end -4.505 -1.5)
			(stroke
				(width 0.05)
				(type solid)
			)
			(layer "F.CrtYd")
		)
		(fp_line
			(start 3.77 -1.51)
			(end 4.505 -1.51)
			(stroke
				(width 0.05)
				(type solid)
			)
			(layer "F.CrtYd")
		)
		(fp_line
			(start 4.505 -1.51)
			(end 4.505 1.5)
			(stroke
				(width 0.05)
				(type solid)
			)
			(layer "F.CrtYd")
		)
		(fp_line
			(start -3.775 -2.4)
			(end -3.775 -1.5)
			(stroke
				(width 0.05)
				(type solid)
			)
			(layer "F.CrtYd")
		)
		(fp_line
			(start -3.775 -2.4)
			(end 3.77 -2.4)
			(stroke
				(width 0.05)
				(type solid)
			)
			(layer "F.CrtYd")
		)
		(fp_line
			(start 3.77 -2.4)
			(end 3.77 -1.51)
			(stroke
				(width 0.05)
				(type solid)
			)
			(layer "F.CrtYd")
		)
		(fp_rect
			(start -3.65 -2.15)
			(end 3.65 2.15)
			(stroke
				(width 0.15)
				(type solid)
			)
			(fill no)
			(layer "F.Fab")
		)
		(pad "1" smd roundrect
			(at -3.1 0 270)
			(size 2.31 2.52)
			(layers "F.Cu" "F.Mask" "F.Paste")
			(roundrect_rratio 0.1)
			(net 227 "+1V0")
			(pintype "passive")
		)
		(pad "2" smd roundrect
			(at 3.1 0 270)
			(size 2.31 2.52)
			(layers "F.Cu" "F.Mask" "F.Paste")
			(roundrect_rratio 0.1)
			(net 1 "GND")
			(pintype "passive")
		)
	)
)
